(kicad_sch
	(version 20250114)
	(generator "eeschema")
	(generator_version "9.0")
	(paper "A3")
	(title_block
		(title "Thunderbolt to 10GbE adapter")
		(date "2026-04-23")
		(rev "1.1.0")
		(company "Antmicro Ltd")
		(comment 1 "www.antmicro.com")
	)
	(rectangle
		(start 223.52 38.1)
		(end 345.44 191.77)
		(stroke
			(width 0.127)
			(type dash)
		)
		(fill
			(type none)
		)
	)
	(rectangle
		(start 88.9 78.74)
		(end 148.59 187.96)
		(stroke
			(width 0.127)
			(type dash)
		)
		(fill
			(type none)
		)
	)
	(text "Common"
		(exclude_from_sim no)
		(at 88.9 208.28 0)
		(effects
			(font
				(size 3.81 3.81)
				(thickness 0.762)
				(bold yes)
			)
		)
	)
	(text "TB to PCIe"
		(exclude_from_sim no)
		(at 93.98 19.05 0)
		(effects
			(font
				(size 3.81 3.81)
				(thickness 0.762)
				(bold yes)
			)
		)
	)
	(text "X710-AT2"
		(exclude_from_sim no)
		(at 234.95 41.91 0)
		(effects
			(font
				(size 2.54 2.54)
				(thickness 0.508)
				(bold yes)
			)
		)
	)
	(text "10G MAC/PHY"
		(exclude_from_sim no)
		(at 299.72 19.05 0)
		(effects
			(font
				(size 3.81 3.81)
				(thickness 0.762)
				(bold yes)
			)
		)
	)
	(text "JHL6340 S LLSQ"
		(exclude_from_sim no)
		(at 106.045 81.915 0)
		(effects
			(font
				(size 2.54 2.54)
				(thickness 0.508)
				(bold yes)
			)
		)
	)
	(junction
		(at 110.49 251.46)
		(diameter 0)
		(color 0 0 0 0)
	)
	(junction
		(at 72.39 259.08)
		(diameter 0)
		(color 0 0 0 0)
	)
	(junction
		(at 83.82 114.3)
		(diameter 0)
		(color 0 0 0 0)
	)
	(junction
		(at 72.39 266.7)
		(diameter 0)
		(color 0 0 0 0)
	)
	(junction
		(at 83.82 121.92)
		(diameter 0)
		(color 0 0 0 0)
	)
	(junction
		(at 227.33 140.97)
		(diameter 0)
		(color 0 0 0 0)
	)
	(junction
		(at 72.39 251.46)
		(diameter 0)
		(color 0 0 0 0)
	)
	(junction
		(at 110.49 266.7)
		(diameter 0)
		(color 0 0 0 0)
	)
	(junction
		(at 110.49 259.08)
		(diameter 0)
		(color 0 0 0 0)
	)
	(wire
		(pts
			(xy 332.74 67.31) (xy 355.6 67.31)
		)
		(stroke
			(width 0)
			(type default)
		)
	)
	(wire
		(pts
			(xy 110.49 259.08) (xy 110.49 266.7)
		)
		(stroke
			(width 0)
			(type default)
		)
	)
	(wire
		(pts
			(xy 185.42 175.26) (xy 142.24 175.26)
		)
		(stroke
			(width 0)
			(type default)
		)
	)
	(bus
		(pts
			(xy 142.24 151.13) (xy 231.14 151.13)
		)
		(stroke
			(width 0)
			(type default)
		)
	)
	(wire
		(pts
			(xy 110.49 243.84) (xy 110.49 251.46)
		)
		(stroke
			(width 0)
			(type default)
		)
	)
	(bus
		(pts
			(xy 69.85 121.92) (xy 83.82 121.92)
		)
		(stroke
			(width 0)
			(type default)
		)
	)
	(wire
		(pts
			(xy 72.39 266.7) (xy 72.39 269.24)
		)
		(stroke
			(width 0)
			(type default)
		)
	)
	(bus
		(pts
			(xy 83.82 67.31) (xy 81.28 64.77)
		)
		(stroke
			(width 0)
			(type default)
		)
	)
	(bus
		(pts
			(xy 332.74 62.23) (xy 355.6 62.23)
		)
		(stroke
			(width 0)
			(type default)
		)
	)
	(bus
		(pts
			(xy 69.85 102.87) (xy 97.79 102.87)
		)
		(stroke
			(width 0)
			(type default)
		)
	)
	(polyline
		(pts
			(xy 177.8 12.7) (xy 177.8 284.48)
		)
		(stroke
			(width 0.254)
			(type dash)
		)
	)
	(wire
		(pts
			(xy 274.32 77.47) (xy 289.56 77.47)
		)
		(stroke
			(width 0)
			(type default)
		)
	)
	(bus
		(pts
			(xy 274.32 62.23) (xy 289.56 62.23)
		)
		(stroke
			(width 0)
			(type default)
		)
	)
	(wire
		(pts
			(xy 69.85 99.06) (xy 97.79 99.06)
		)
		(stroke
			(width 0)
			(type default)
		)
	)
	(bus
		(pts
			(xy 83.82 132.08) (xy 81.28 134.62)
		)
		(stroke
			(width 0)
			(type default)
		)
	)
	(bus
		(pts
			(xy 69.85 134.62) (xy 81.28 134.62)
		)
		(stroke
			(width 0)
			(type default)
		)
	)
	(wire
		(pts
			(xy 332.74 64.77) (xy 355.6 64.77)
		)
		(stroke
			(width 0)
			(type default)
		)
	)
	(bus
		(pts
			(xy 69.85 110.49) (xy 97.79 110.49)
		)
		(stroke
			(width 0)
			(type default)
		)
	)
	(wire
		(pts
			(xy 110.49 251.46) (xy 113.03 251.46)
		)
		(stroke
			(width 0)
			(type default)
		)
	)
	(bus
		(pts
			(xy 69.85 118.11) (xy 97.79 118.11)
		)
		(stroke
			(width 0)
			(type default)
		)
	)
	(bus
		(pts
			(xy 215.9 73.66) (xy 231.14 73.66)
		)
		(stroke
			(width 0)
			(type default)
		)
	)
	(wire
		(pts
			(xy 72.39 259.08) (xy 72.39 266.7)
		)
		(stroke
			(width 0)
			(type default)
		)
	)
	(wire
		(pts
			(xy 74.93 243.84) (xy 72.39 243.84)
		)
		(stroke
			(width 0)
			(type default)
		)
	)
	(wire
		(pts
			(xy 72.39 251.46) (xy 74.93 251.46)
		)
		(stroke
			(width 0)
			(type default)
		)
	)
	(wire
		(pts
			(xy 110.49 251.46) (xy 110.49 259.08)
		)
		(stroke
			(width 0)
			(type default)
		)
	)
	(wire
		(pts
			(xy 72.39 251.46) (xy 72.39 259.08)
		)
		(stroke
			(width 0)
			(type default)
		)
	)
	(wire
		(pts
			(xy 69.85 144.78) (xy 97.79 144.78)
		)
		(stroke
			(width 0)
			(type default)
		)
	)
	(bus
		(pts
			(xy 83.82 114.3) (xy 97.79 114.3)
		)
		(stroke
			(width 0)
			(type default)
		)
	)
	(wire
		(pts
			(xy 142.24 143.51) (xy 231.14 143.51)
		)
		(stroke
			(width 0)
			(type default)
		)
	)
	(bus
		(pts
			(xy 69.85 106.68) (xy 97.79 106.68)
		)
		(stroke
			(width 0)
			(type default)
		)
	)
	(wire
		(pts
			(xy 332.74 86.36) (xy 355.6 86.36)
		)
		(stroke
			(width 0)
			(type default)
		)
	)
	(bus
		(pts
			(xy 83.82 114.3) (xy 83.82 67.31)
		)
		(stroke
			(width 0)
			(type default)
		)
	)
	(wire
		(pts
			(xy 113.03 266.7) (xy 110.49 266.7)
		)
		(stroke
			(width 0)
			(type default)
		)
	)
	(wire
		(pts
			(xy 142.24 140.97) (xy 227.33 140.97)
		)
		(stroke
			(width 0)
			(type default)
		)
	)
	(wire
		(pts
			(xy 113.03 243.84) (xy 110.49 243.84)
		)
		(stroke
			(width 0)
			(type default)
		)
	)
	(wire
		(pts
			(xy 274.32 109.22) (xy 355.6 109.22)
		)
		(stroke
			(width 0)
			(type default)
		)
	)
	(polyline
		(pts
			(xy 12.7 200.66) (xy 177.8 200.66)
		)
		(stroke
			(width 0.254)
			(type dash)
		)
	)
	(wire
		(pts
			(xy 74.93 266.7) (xy 72.39 266.7)
		)
		(stroke
			(width 0)
			(type default)
		)
	)
	(bus
		(pts
			(xy 69.85 64.77) (xy 81.28 64.77)
		)
		(stroke
			(width 0)
			(type default)
		)
	)
	(wire
		(pts
			(xy 274.32 64.77) (xy 289.56 64.77)
		)
		(stroke
			(width 0)
			(type default)
		)
	)
	(bus
		(pts
			(xy 83.82 121.92) (xy 83.82 132.08)
		)
		(stroke
			(width 0)
			(type default)
		)
	)
	(wire
		(pts
			(xy 110.49 259.08) (xy 113.03 259.08)
		)
		(stroke
			(width 0)
			(type default)
		)
	)
	(wire
		(pts
			(xy 72.39 243.84) (xy 72.39 251.46)
		)
		(stroke
			(width 0)
			(type default)
		)
	)
	(wire
		(pts
			(xy 227.33 95.25) (xy 227.33 140.97)
		)
		(stroke
			(width 0)
			(type default)
		)
	)
	(bus
		(pts
			(xy 332.74 83.82) (xy 355.6 83.82)
		)
		(stroke
			(width 0)
			(type default)
		)
	)
	(wire
		(pts
			(xy 227.33 95.25) (xy 231.14 95.25)
		)
		(stroke
			(width 0)
			(type default)
		)
	)
	(bus
		(pts
			(xy 83.82 121.92) (xy 97.79 121.92)
		)
		(stroke
			(width 0)
			(type default)
		)
	)
	(wire
		(pts
			(xy 274.32 106.68) (xy 355.6 106.68)
		)
		(stroke
			(width 0)
			(type default)
		)
	)
	(wire
		(pts
			(xy 274.32 67.31) (xy 289.56 67.31)
		)
		(stroke
			(width 0)
			(type default)
		)
	)
	(bus
		(pts
			(xy 142.24 148.59) (xy 231.14 148.59)
		)
		(stroke
			(width 0)
			(type default)
		)
	)
	(wire
		(pts
			(xy 332.74 88.9) (xy 355.6 88.9)
		)
		(stroke
			(width 0)
			(type default)
		)
	)
	(wire
		(pts
			(xy 110.49 266.7) (xy 110.49 269.24)
		)
		(stroke
			(width 0)
			(type default)
		)
	)
	(wire
		(pts
			(xy 69.85 95.25) (xy 97.79 95.25)
		)
		(stroke
			(width 0)
			(type default)
		)
	)
	(wire
		(pts
			(xy 72.39 259.08) (xy 74.93 259.08)
		)
		(stroke
			(width 0)
			(type default)
		)
	)
	(wire
		(pts
			(xy 227.33 140.97) (xy 231.14 140.97)
		)
		(stroke
			(width 0)
			(type default)
		)
	)
	(bus
		(pts
			(xy 69.85 114.3) (xy 83.82 114.3)
		)
		(stroke
			(width 0)
			(type default)
		)
	)
	(symbol
		(lib_id "antmicroMechanicalParts:MP_Pad6mm_Drill3.2mm")
		(at 74.93 259.08 0)
		(unit 1)
		(exclude_from_sim no)
		(in_bom no)
		(on_board yes)
		(dnp no)
		(fields_autoplaced yes)
		(property "Reference" "MP3"
			(at 83.82 257.81 0)
			(effects
				(font
					(size 1.27 1.27)
					(thickness 0.15)
				)
				(justify left)
			)
		)
		(property "Value" "MP_Pad6mm_Drill3.2mm"
			(at 83.82 260.35 0)
			(effects
				(font
					(size 1.27 1.27)
					(thickness 0.15)
				)
				(justify left)
			)
		)
		(property "Footprint" "antmicro-footprints:MP_Pad6mm_Drill3.2mm"
			(at 95.25 266.7 0)
			(effects
				(font
					(size 1.27 1.27)
					(thickness 0.15)
				)
				(justify left bottom)
				(hide yes)
			)
		)
		(property "Datasheet" ""
			(at 91.77 274.65 0)
			(effects
				(font
					(size 1.27 1.27)
					(thickness 0.15)
				)
				(justify left bottom)
				(hide yes)
			)
		)
		(property "Description" "Mechanical part"
			(at 74.93 259.08 0)
			(effects
				(font
					(size 1.27 1.27)
				)
				(hide yes)
			)
		)
		(property "Author" "Antmicro"
			(at 95.25 269.24 0)
			(effects
				(font
					(size 1.27 1.27)
					(thickness 0.15)
				)
				(justify left bottom)
				(hide yes)
			)
		)
		(property "License" "Apache-2.0"
			(at 95.25 271.78 0)
			(effects
				(font
					(size 1.27 1.27)
					(thickness 0.15)
				)
				(justify left bottom)
				(hide yes)
			)
		)
		(pin "1"
		)
		(instances
			(project "OCuLink to 10GbE adapter"
				(path ""
					(reference "MP3")
					(unit 1)
				)
			)
			(project "thunderbolt-to-10gbe-adapter"
				(path ""
					(reference "MP3")
					(unit 1)
				)
			)
		)
	)
	(symbol
		(lib_id "antmicroFiducialMarks:Fiducial_1mm_Mask2mm")
		(at 148.59 232.41 0)
		(unit 1)
		(exclude_from_sim no)
		(in_bom no)
		(on_board yes)
		(dnp no)
		(fields_autoplaced yes)
		(property "Reference" "FD5"
			(at 152.4 231.14 0)
			(effects
				(font
					(size 1.27 1.27)
					(thickness 0.15)
				)
				(justify left)
			)
		)
		(property "Value" "Fiducial_1mm_Mask2mm"
			(at 152.4 233.68 0)
			(effects
				(font
					(size 1.27 1.27)
					(thickness 0.15)
				)
				(justify left)
			)
		)
		(property "Footprint" "antmicro-footprints:Fiducial_1mm_Mask2mm"
			(at 157.48 237.49 0)
			(effects
				(font
					(size 1.27 1.27)
					(thickness 0.15)
				)
				(justify left bottom)
				(hide yes)
			)
		)
		(property "Datasheet" ""
			(at 157.81 242.9 0)
			(effects
				(font
					(size 1.27 1.27)
					(thickness 0.15)
				)
				(justify left bottom)
				(hide yes)
			)
		)
		(property "Description" "Fiducial mask"
			(at 157.81 245.44 0)
			(effects
				(font
					(size 1.27 1.27)
				)
				(justify left bottom)
				(hide yes)
			)
		)
		(property "Author" "Antmicro"
			(at 157.48 240.03 0)
			(effects
				(font
					(size 1.27 1.27)
					(thickness 0.15)
				)
				(justify left bottom)
				(hide yes)
			)
		)
		(property "License" "Apache-2.0"
			(at 157.48 242.57 0)
			(effects
				(font
					(size 1.27 1.27)
					(thickness 0.15)
				)
				(justify left bottom)
				(hide yes)
			)
		)
		(instances
			(project "thunderbolt-to-10gbe-adapter"
				(path ""
					(reference "FD5")
					(unit 1)
				)
			)
		)
	)
	(symbol
		(lib_id "antmicroMechanicalParts:Lightpipe_Mentor_1271.1001")
		(at 44.45 256.54 0)
		(unit 1)
		(exclude_from_sim no)
		(in_bom yes)
		(on_board yes)
		(dnp no)
		(fields_autoplaced yes)
		(property "Reference" "H2"
			(at 50.292 255.0744 0)
			(effects
				(font
					(size 1.27 1.27)
					(thickness 0.15)
				)
				(justify left)
			)
		)
		(property "Value" "Lightpipe_Mentor_1271.1001"
			(at 64.77 264.16 0)
			(effects
				(font
					(size 1.27 1.27)
					(thickness 0.15)
				)
				(justify left bottom)
				(hide yes)
			)
		)
		(property "Footprint" "antmicro-footprints:Mech_Lightpipe_Mentor_1271.1001"
			(at 64.77 266.7 0)
			(effects
				(font
					(size 1.27 1.27)
					(thickness 0.15)
				)
				(justify left bottom)
				(hide yes)
			)
		)
		(property "Datasheet" "https://www.mentor.de.com/productpdfs/ll/ll14-20.pdf"
			(at 64.77 269.24 0)
			(effects
				(font
					(size 1.27 1.27)
					(thickness 0.15)
				)
				(justify left bottom)
				(hide yes)
			)
		)
		(property "Description" "Light Pipe, 14.45 mm, 1 Pipe, Circular, PC Board, Transparent"
			(at 44.45 256.54 0)
			(effects
				(font
					(size 1.27 1.27)
				)
				(hide yes)
			)
		)
		(property "MPN" "1271.1001"
			(at 50.292 257.5981 0)
			(effects
				(font
					(size 1.27 1.27)
					(thickness 0.15)
				)
				(justify left)
			)
		)
		(property "Manufacturer" "Mentor Worldwide"
			(at 64.77 271.78 0)
			(effects
				(font
					(size 1.27 1.27)
					(thickness 0.15)
				)
				(justify left bottom)
				(hide yes)
			)
		)
		(property "Author" "Antmicro"
			(at 64.77 274.32 0)
			(effects
				(font
					(size 1.27 1.27)
					(thickness 0.15)
				)
				(justify left bottom)
				(hide yes)
			)
		)
		(property "License" "Apache-2.0"
			(at 64.77 276.86 0)
			(effects
				(font
					(size 1.27 1.27)
					(thickness 0.15)
				)
				(justify left bottom)
				(hide yes)
			)
		)
		(instances
			(project "thunderbolt-to-10gbe-adapter"
				(path ""
					(reference "H2")
					(unit 1)
				)
			)
		)
	)
	(symbol
		(lib_id "antmicroFiducialMarks:Fiducial_1mm_Mask2mm")
		(at 148.59 237.49 0)
		(unit 1)
		(exclude_from_sim no)
		(in_bom no)
		(on_board yes)
		(dnp no)
		(fields_autoplaced yes)
		(property "Reference" "FD6"
			(at 152.4 236.22 0)
			(effects
				(font
					(size 1.27 1.27)
					(thickness 0.15)
				)
				(justify left)
			)
		)
		(property "Value" "Fiducial_1mm_Mask2mm"
			(at 152.4 238.76 0)
			(effects
				(font
					(size 1.27 1.27)
					(thickness 0.15)
				)
				(justify left)
			)
		)
		(property "Footprint" "antmicro-footprints:Fiducial_1mm_Mask2mm"
			(at 157.48 242.57 0)
			(effects
				(font
					(size 1.27 1.27)
					(thickness 0.15)
				)
				(justify left bottom)
				(hide yes)
			)
		)
		(property "Datasheet" ""
			(at 157.81 247.98 0)
			(effects
				(font
					(size 1.27 1.27)
					(thickness 0.15)
				)
				(justify left bottom)
				(hide yes)
			)
		)
		(property "Description" "Fiducial mask"
			(at 157.81 250.52 0)
			(effects
				(font
					(size 1.27 1.27)
				)
				(justify left bottom)
				(hide yes)
			)
		)
		(property "Author" "Antmicro"
			(at 157.48 245.11 0)
			(effects
				(font
					(size 1.27 1.27)
					(thickness 0.15)
				)
				(justify left bottom)
				(hide yes)
			)
		)
		(property "License" "Apache-2.0"
			(at 157.48 247.65 0)
			(effects
				(font
					(size 1.27 1.27)
					(thickness 0.15)
				)
				(justify left bottom)
				(hide yes)
			)
		)
		(instances
			(project "thunderbolt-to-10gbe-adapter"
				(path ""
					(reference "FD6")
					(unit 1)
				)
			)
		)
	)
	(symbol
		(lib_id "antmicroFiducialMarks:Fiducial_1mm_Mask2mm")
		(at 148.59 247.65 0)
		(unit 1)
		(exclude_from_sim no)
		(in_bom no)
		(on_board yes)
		(dnp no)
		(fields_autoplaced yes)
		(property "Reference" "FD8"
			(at 152.4 246.38 0)
			(effects
				(font
					(size 1.27 1.27)
					(thickness 0.15)
				)
				(justify left)
			)
		)
		(property "Value" "Fiducial_1mm_Mask2mm"
			(at 152.4 248.92 0)
			(effects
				(font
					(size 1.27 1.27)
					(thickness 0.15)
				)
				(justify left)
			)
		)
		(property "Footprint" "antmicro-footprints:Fiducial_1mm_Mask2mm"
			(at 157.48 252.73 0)
			(effects
				(font
					(size 1.27 1.27)
					(thickness 0.15)
				)
				(justify left bottom)
				(hide yes)
			)
		)
		(property "Datasheet" ""
			(at 157.81 258.14 0)
			(effects
				(font
					(size 1.27 1.27)
					(thickness 0.15)
				)
				(justify left bottom)
				(hide yes)
			)
		)
		(property "Description" "Fiducial mask"
			(at 157.81 260.68 0)
			(effects
				(font
					(size 1.27 1.27)
				)
				(justify left bottom)
				(hide yes)
			)
		)
		(property "Author" "Antmicro"
			(at 157.48 255.27 0)
			(effects
				(font
					(size 1.27 1.27)
					(thickness 0.15)
				)
				(justify left bottom)
				(hide yes)
			)
		)
		(property "License" "Apache-2.0"
			(at 157.48 257.81 0)
			(effects
				(font
					(size 1.27 1.27)
					(thickness 0.15)
				)
				(justify left bottom)
				(hide yes)
			)
		)
		(instances
			(project "thunderbolt-to-10gbe-adapter"
				(path ""
					(reference "FD8")
					(unit 1)
				)
			)
		)
	)
	(symbol
		(lib_id "antmicroMechanicalParts:MP_Pad6mm_Drill3.2mm")
		(at 113.03 243.84 0)
		(unit 1)
		(exclude_from_sim no)
		(in_bom no)
		(on_board yes)
		(dnp no)
		(fields_autoplaced yes)
		(property "Reference" "MP5"
			(at 121.92 242.57 0)
			(effects
				(font
					(size 1.27 1.27)
					(thickness 0.15)
				)
				(justify left)
			)
		)
		(property "Value" "MP_Pad6mm_Drill3.2mm"
			(at 121.92 245.11 0)
			(effects
				(font
					(size 1.27 1.27)
					(thickness 0.15)
				)
				(justify left)
			)
		)
		(property "Footprint" "antmicro-footprints:MP_Pad6mm_Drill3.2mm"
			(at 133.35 251.46 0)
			(effects
				(font
					(size 1.27 1.27)
					(thickness 0.15)
				)
				(justify left bottom)
				(hide yes)
			)
		)
		(property "Datasheet" ""
			(at 129.87 259.41 0)
			(effects
				(font
					(size 1.27 1.27)
					(thickness 0.15)
				)
				(justify left bottom)
				(hide yes)
			)
		)
		(property "Description" "Mechanical part"
			(at 113.03 243.84 0)
			(effects
				(font
					(size 1.27 1.27)
				)
				(hide yes)
			)
		)
		(property "Author" "Antmicro"
			(at 133.35 254 0)
			(effects
				(font
					(size 1.27 1.27)
					(thickness 0.15)
				)
				(justify left bottom)
				(hide yes)
			)
		)
		(property "License" "Apache-2.0"
			(at 133.35 256.54 0)
			(effects
				(font
					(size 1.27 1.27)
					(thickness 0.15)
				)
				(justify left bottom)
				(hide yes)
			)
		)
		(pin "1"
		)
		(instances
			(project "oculink-to-10gbe-adapter"
				(path ""
					(reference "MP5")
					(unit 1)
				)
			)
			(project "thunderbolt-to-10gbe-adapter"
				(path ""
					(reference "MP5")
					(unit 1)
				)
			)
		)
	)
	(symbol
		(lib_id "antmicroMechanicalParts:MP_Pad6mm_Drill3.2mm")
		(at 113.03 266.7 0)
		(unit 1)
		(exclude_from_sim no)
		(in_bom no)
		(on_board yes)
		(dnp no)
		(fields_autoplaced yes)
		(property "Reference" "MP8"
			(at 121.92 265.43 0)
			(effects
				(font
					(size 1.27 1.27)
					(thickness 0.15)
				)
				(justify left)
			)
		)
		(property "Value" "MP_Pad6mm_Drill3.2mm"
			(at 121.92 267.97 0)
			(effects
				(font
					(size 1.27 1.27)
					(thickness 0.15)
				)
				(justify left)
			)
		)
		(property "Footprint" "antmicro-footprints:MP_Pad6mm_Drill3.2mm"
			(at 133.35 274.32 0)
			(effects
				(font
					(size 1.27 1.27)
					(thickness 0.15)
				)
				(justify left bottom)
				(hide yes)
			)
		)
		(property "Datasheet" ""
			(at 129.87 282.27 0)
			(effects
				(font
					(size 1.27 1.27)
					(thickness 0.15)
				)
				(justify left bottom)
				(hide yes)
			)
		)
		(property "Description" "Mechanical part"
			(at 113.03 266.7 0)
			(effects
				(font
					(size 1.27 1.27)
				)
				(hide yes)
			)
		)
		(property "Author" "Antmicro"
			(at 133.35 276.86 0)
			(effects
				(font
					(size 1.27 1.27)
					(thickness 0.15)
				)
				(justify left bottom)
				(hide yes)
			)
		)
		(property "License" "Apache-2.0"
			(at 133.35 279.4 0)
			(effects
				(font
					(size 1.27 1.27)
					(thickness 0.15)
				)
				(justify left bottom)
				(hide yes)
			)
		)
		(pin "1"
		)
		(instances
			(project "oculink-to-10gbe-adapter"
				(path ""
					(reference "MP8")
					(unit 1)
				)
			)
			(project "thunderbolt-to-10gbe-adapter"
				(path ""
					(reference "MP8")
					(unit 1)
				)
			)
		)
	)
	(symbol
		(lib_id "antmicroMechanicalParts:Lightpipe_Mentor_1271.1001")
		(at 21.59 256.54 0)
		(unit 1)
		(exclude_from_sim no)
		(in_bom yes)
		(on_board yes)
		(dnp yes)
		(fields_autoplaced yes)
		(property "Reference" "H5"
			(at 27.432 255.0744 0)
			(effects
				(font
					(size 1.27 1.27)
					(thickness 0.15)
				)
				(justify left)
			)
		)
		(property "Value" "Lightpipe_Mentor_1271.1001"
			(at 41.91 264.16 0)
			(effects
				(font
					(size 1.27 1.27)
					(thickness 0.15)
				)
				(justify left bottom)
				(hide yes)
			)
		)
		(property "Footprint" "antmicro-footprints:Mech_Lightpipe_Mentor_1271.1001"
			(at 41.91 266.7 0)
			(effects
				(font
					(size 1.27 1.27)
					(thickness 0.15)
				)
				(justify left bottom)
				(hide yes)
			)
		)
		(property "Datasheet" "https://www.mentor.de.com/productpdfs/ll/ll14-20.pdf"
			(at 41.91 269.24 0)
			(effects
				(font
					(size 1.27 1.27)
					(thickness 0.15)
				)
				(justify left bottom)
				(hide yes)
			)
		)
		(property "Description" "Light Pipe, 14.45 mm, 1 Pipe, Circular, PC Board, Transparent"
			(at 21.59 256.54 0)
			(effects
				(font
					(size 1.27 1.27)
				)
				(hide yes)
			)
		)
		(property "MPN" "1271.1001"
			(at 27.432 257.5981 0)
			(effects
				(font
					(size 1.27 1.27)
					(thickness 0.15)
				)
				(justify left)
			)
		)
		(property "Manufacturer" "Mentor Worldwide"
			(at 41.91 271.78 0)
			(effects
				(font
					(size 1.27 1.27)
					(thickness 0.15)
				)
				(justify left bottom)
				(hide yes)
			)
		)
		(property "Author" "Antmicro"
			(at 41.91 274.32 0)
			(effects
				(font
					(size 1.27 1.27)
					(thickness 0.15)
				)
				(justify left bottom)
				(hide yes)
			)
		)
		(property "License" "Apache-2.0"
			(at 41.91 276.86 0)
			(effects
				(font
					(size 1.27 1.27)
					(thickness 0.15)
				)
				(justify left bottom)
				(hide yes)
			)
		)
		(instances
			(project "thunderbolt-to-10gbe-adapter"
				(path ""
					(reference "H5")
					(unit 1)
				)
			)
		)
	)
	(symbol
		(lib_id "antmicroMechanicalParts:MP_Pad6mm_Drill3.2mm")
		(at 113.03 251.46 0)
		(unit 1)
		(exclude_from_sim no)
		(in_bom no)
		(on_board yes)
		(dnp no)
		(fields_autoplaced yes)
		(property "Reference" "MP6"
			(at 121.92 250.19 0)
			(effects
				(font
					(size 1.27 1.27)
					(thickness 0.15)
				)
				(justify left)
			)
		)
		(property "Value" "MP_Pad6mm_Drill3.2mm"
			(at 121.92 252.73 0)
			(effects
				(font
					(size 1.27 1.27)
					(thickness 0.15)
				)
				(justify left)
			)
		)
		(property "Footprint" "antmicro-footprints:MP_Pad6mm_Drill3.2mm"
			(at 133.35 259.08 0)
			(effects
				(font
					(size 1.27 1.27)
					(thickness 0.15)
				)
				(justify left bottom)
				(hide yes)
			)
		)
		(property "Datasheet" ""
			(at 129.87 267.03 0)
			(effects
				(font
					(size 1.27 1.27)
					(thickness 0.15)
				)
				(justify left bottom)
				(hide yes)
			)
		)
		(property "Description" "Mechanical part"
			(at 113.03 251.46 0)
			(effects
				(font
					(size 1.27 1.27)
				)
				(hide yes)
			)
		)
		(property "Author" "Antmicro"
			(at 133.35 261.62 0)
			(effects
				(font
					(size 1.27 1.27)
					(thickness 0.15)
				)
				(justify left bottom)
				(hide yes)
			)
		)
		(property "License" "Apache-2.0"
			(at 133.35 264.16 0)
			(effects
				(font
					(size 1.27 1.27)
					(thickness 0.15)
				)
				(justify left bottom)
				(hide yes)
			)
		)
		(pin "1"
		)
		(instances
			(project "oculink-to-10gbe-adapter"
				(path ""
					(reference "MP6")
					(unit 1)
				)
			)
			(project "thunderbolt-to-10gbe-adapter"
				(path ""
					(reference "MP6")
					(unit 1)
				)
			)
		)
	)
	(symbol
		(lib_id "antmicroFiducialMarks:Fiducial_1mm_Mask2mm")
		(at 148.59 227.33 0)
		(unit 1)
		(exclude_from_sim no)
		(in_bom no)
		(on_board yes)
		(dnp no)
		(fields_autoplaced yes)
		(property "Reference" "FD4"
			(at 152.4 226.06 0)
			(effects
				(font
					(size 1.27 1.27)
					(thickness 0.15)
				)
				(justify left)
			)
		)
		(property "Value" "Fiducial_1mm_Mask2mm"
			(at 152.4 228.6 0)
			(effects
				(font
					(size 1.27 1.27)
					(thickness 0.15)
				)
				(justify left)
			)
		)
		(property "Footprint" "antmicro-footprints:Fiducial_1mm_Mask2mm"
			(at 157.48 232.41 0)
			(effects
				(font
					(size 1.27 1.27)
					(thickness 0.15)
				)
				(justify left bottom)
				(hide yes)
			)
		)
		(property "Datasheet" ""
			(at 157.81 237.82 0)
			(effects
				(font
					(size 1.27 1.27)
					(thickness 0.15)
				)
				(justify left bottom)
				(hide yes)
			)
		)
		(property "Description" "Fiducial mask"
			(at 157.81 240.36 0)
			(effects
				(font
					(size 1.27 1.27)
				)
				(justify left bottom)
				(hide yes)
			)
		)
		(property "Author" "Antmicro"
			(at 157.48 234.95 0)
			(effects
				(font
					(size 1.27 1.27)
					(thickness 0.15)
				)
				(justify left bottom)
				(hide yes)
			)
		)
		(property "License" "Apache-2.0"
			(at 157.48 237.49 0)
			(effects
				(font
					(size 1.27 1.27)
					(thickness 0.15)
				)
				(justify left bottom)
				(hide yes)
			)
		)
		(instances
			(project "thunderbolt-to-10gbe-adapter"
				(path ""
					(reference "FD4")
					(unit 1)
				)
			)
		)
	)
	(symbol
		(lib_id "antmicroFiducialMarks:Fiducial_1mm_Mask2mm")
		(at 148.59 222.25 0)
		(unit 1)
		(exclude_from_sim no)
		(in_bom no)
		(on_board yes)
		(dnp no)
		(fields_autoplaced yes)
		(property "Reference" "FD3"
			(at 152.4 220.98 0)
			(effects
				(font
					(size 1.27 1.27)
					(thickness 0.15)
				)
				(justify left)
			)
		)
		(property "Value" "Fiducial_1mm_Mask2mm"
			(at 152.4 223.52 0)
			(effects
				(font
					(size 1.27 1.27)
					(thickness 0.15)
				)
				(justify left)
			)
		)
		(property "Footprint" "antmicro-footprints:Fiducial_1mm_Mask2mm"
			(at 157.48 227.33 0)
			(effects
				(font
					(size 1.27 1.27)
					(thickness 0.15)
				)
				(justify left bottom)
				(hide yes)
			)
		)
		(property "Datasheet" ""
			(at 157.81 232.74 0)
			(effects
				(font
					(size 1.27 1.27)
					(thickness 0.15)
				)
				(justify left bottom)
				(hide yes)
			)
		)
		(property "Description" "Fiducial mask"
			(at 157.81 235.28 0)
			(effects
				(font
					(size 1.27 1.27)
				)
				(justify left bottom)
				(hide yes)
			)
		)
		(property "Author" "Antmicro"
			(at 157.48 229.87 0)
			(effects
				(font
					(size 1.27 1.27)
					(thickness 0.15)
				)
				(justify left bottom)
				(hide yes)
			)
		)
		(property "License" "Apache-2.0"
			(at 157.48 232.41 0)
			(effects
				(font
					(size 1.27 1.27)
					(thickness 0.15)
				)
				(justify left bottom)
				(hide yes)
			)
		)
		(instances
			(project "thunderbolt-to-10gbe-adapter"
				(path ""
					(reference "FD3")
					(unit 1)
				)
			)
		)
	)
	(symbol
		(lib_id "antmicroFiducialMarks:Fiducial_1mm_Mask2mm")
		(at 148.59 212.09 0)
		(unit 1)
		(exclude_from_sim no)
		(in_bom no)
		(on_board yes)
		(dnp no)
		(fields_autoplaced yes)
		(property "Reference" "FD1"
			(at 152.4 210.82 0)
			(effects
				(font
					(size 1.27 1.27)
					(thickness 0.15)
				)
				(justify left)
			)
		)
		(property "Value" "Fiducial_1mm_Mask2mm"
			(at 152.4 213.36 0)
			(effects
				(font
					(size 1.27 1.27)
					(thickness 0.15)
				)
				(justify left)
			)
		)
		(property "Footprint" "antmicro-footprints:Fiducial_1mm_Mask2mm"
			(at 157.48 217.17 0)
			(effects
				(font
					(size 1.27 1.27)
					(thickness 0.15)
				)
				(justify left bottom)
				(hide yes)
			)
		)
		(property "Datasheet" ""
			(at 157.81 222.58 0)
			(effects
				(font
					(size 1.27 1.27)
					(thickness 0.15)
				)
				(justify left bottom)
				(hide yes)
			)
		)
		(property "Description" "Fiducial mask"
			(at 157.81 225.12 0)
			(effects
				(font
					(size 1.27 1.27)
				)
				(justify left bottom)
				(hide yes)
			)
		)
		(property "Author" "Antmicro"
			(at 157.48 219.71 0)
			(effects
				(font
					(size 1.27 1.27)
					(thickness 0.15)
				)
				(justify left bottom)
				(hide yes)
			)
		)
		(property "License" "Apache-2.0"
			(at 157.48 222.25 0)
			(effects
				(font
					(size 1.27 1.27)
					(thickness 0.15)
				)
				(justify left bottom)
				(hide yes)
			)
		)
		(instances
			(project "thunderbolt-to-10gbe-adapter"
				(path ""
					(reference "FD1")
					(unit 1)
				)
			)
		)
	)
	(symbol
		(lib_id "antmicroMechanicalParts:MP_Pad6mm_Drill3.2mm")
		(at 74.93 243.84 0)
		(unit 1)
		(exclude_from_sim no)
		(in_bom no)
		(on_board yes)
		(dnp no)
		(fields_autoplaced yes)
		(property "Reference" "MP1"
			(at 83.82 242.57 0)
			(effects
				(font
					(size 1.27 1.27)
					(thickness 0.15)
				)
				(justify left)
			)
		)
		(property "Value" "MP_Pad6mm_Drill3.2mm"
			(at 83.82 245.11 0)
			(effects
				(font
					(size 1.27 1.27)
					(thickness 0.15)
				)
				(justify left)
			)
		)
		(property "Footprint" "antmicro-footprints:MP_Pad6mm_Drill3.2mm"
			(at 95.25 251.46 0)
			(effects
				(font
					(size 1.27 1.27)
					(thickness 0.15)
				)
				(justify left bottom)
				(hide yes)
			)
		)
		(property "Datasheet" ""
			(at 91.77 259.41 0)
			(effects
				(font
					(size 1.27 1.27)
					(thickness 0.15)
				)
				(justify left bottom)
				(hide yes)
			)
		)
		(property "Description" "Mechanical part"
			(at 74.93 243.84 0)
			(effects
				(font
					(size 1.27 1.27)
				)
				(hide yes)
			)
		)
		(property "Author" "Antmicro"
			(at 95.25 254 0)
			(effects
				(font
					(size 1.27 1.27)
					(thickness 0.15)
				)
				(justify left bottom)
				(hide yes)
			)
		)
		(property "License" "Apache-2.0"
			(at 95.25 256.54 0)
			(effects
				(font
					(size 1.27 1.27)
					(thickness 0.15)
				)
				(justify left bottom)
				(hide yes)
			)
		)
		(pin "1"
		)
		(instances
			(project ""
				(path ""
					(reference "MP1")
					(unit 1)
				)
			)
			(project "thunderbolt-to-10gbe-adapter"
				(path ""
					(reference "MP1")
					(unit 1)
				)
			)
		)
	)
	(symbol
		(lib_id "antmicroMechanicalParts:MP_Pad6mm_Drill3.2mm")
		(at 74.93 266.7 0)
		(unit 1)
		(exclude_from_sim no)
		(in_bom no)
		(on_board yes)
		(dnp no)
		(fields_autoplaced yes)
		(property "Reference" "MP4"
			(at 83.82 265.43 0)
			(effects
				(font
					(size 1.27 1.27)
					(thickness 0.15)
				)
				(justify left)
			)
		)
		(property "Value" "MP_Pad6mm_Drill3.2mm"
			(at 83.82 267.97 0)
			(effects
				(font
					(size 1.27 1.27)
					(thickness 0.15)
				)
				(justify left)
			)
		)
		(property "Footprint" "antmicro-footprints:MP_Pad6mm_Drill3.2mm"
			(at 95.25 274.32 0)
			(effects
				(font
					(size 1.27 1.27)
					(thickness 0.15)
				)
				(justify left bottom)
				(hide yes)
			)
		)
		(property "Datasheet" ""
			(at 91.77 282.27 0)
			(effects
				(font
					(size 1.27 1.27)
					(thickness 0.15)
				)
				(justify left bottom)
				(hide yes)
			)
		)
		(property "Description" "Mechanical part"
			(at 74.93 266.7 0)
			(effects
				(font
					(size 1.27 1.27)
				)
				(hide yes)
			)
		)
		(property "Author" "Antmicro"
			(at 95.25 276.86 0)
			(effects
				(font
					(size 1.27 1.27)
					(thickness 0.15)
				)
				(justify left bottom)
				(hide yes)
			)
		)
		(property "License" "Apache-2.0"
			(at 95.25 279.4 0)
			(effects
				(font
					(size 1.27 1.27)
					(thickness 0.15)
				)
				(justify left bottom)
				(hide yes)
			)
		)
		(pin "1"
		)
		(instances
			(project "OCuLink to 10GbE adapter"
				(path ""
					(reference "MP4")
					(unit 1)
				)
			)
			(project "thunderbolt-to-10gbe-adapter"
				(path ""
					(reference "MP4")
					(unit 1)
				)
			)
		)
	)
	(symbol
		(lib_id "antmicroMechanicalParts:MP_Pad6mm_Drill3.2mm")
		(at 74.93 251.46 0)
		(unit 1)
		(exclude_from_sim no)
		(in_bom no)
		(on_board yes)
		(dnp no)
		(fields_autoplaced yes)
		(property "Reference" "MP2"
			(at 83.82 250.19 0)
			(effects
				(font
					(size 1.27 1.27)
					(thickness 0.15)
				)
				(justify left)
			)
		)
		(property "Value" "MP_Pad6mm_Drill3.2mm"
			(at 83.82 252.73 0)
			(effects
				(font
					(size 1.27 1.27)
					(thickness 0.15)
				)
				(justify left)
			)
		)
		(property "Footprint" "antmicro-footprints:MP_Pad6mm_Drill3.2mm"
			(at 95.25 259.08 0)
			(effects
				(font
					(size 1.27 1.27)
					(thickness 0.15)
				)
				(justify left bottom)
				(hide yes)
			)
		)
		(property "Datasheet" ""
			(at 91.77 267.03 0)
			(effects
				(font
					(size 1.27 1.27)
					(thickness 0.15)
				)
				(justify left bottom)
				(hide yes)
			)
		)
		(property "Description" "Mechanical part"
			(at 74.93 251.46 0)
			(effects
				(font
					(size 1.27 1.27)
				)
				(hide yes)
			)
		)
		(property "Author" "Antmicro"
			(at 95.25 261.62 0)
			(effects
				(font
					(size 1.27 1.27)
					(thickness 0.15)
				)
				(justify left bottom)
				(hide yes)
			)
		)
		(property "License" "Apache-2.0"
			(at 95.25 264.16 0)
			(effects
				(font
					(size 1.27 1.27)
					(thickness 0.15)
				)
				(justify left bottom)
				(hide yes)
			)
		)
		(pin "1"
		)
		(instances
			(project "OCuLink to 10GbE adapter"
				(path ""
					(reference "MP2")
					(unit 1)
				)
			)
			(project "thunderbolt-to-10gbe-adapter"
				(path ""
					(reference "MP2")
					(unit 1)
				)
			)
		)
	)
	(symbol
		(lib_id "antmicroFiducialMarks:Fiducial_1mm_Mask2mm")
		(at 148.59 217.17 0)
		(unit 1)
		(exclude_from_sim no)
		(in_bom no)
		(on_board yes)
		(dnp no)
		(fields_autoplaced yes)
		(property "Reference" "FD2"
			(at 152.4 215.9 0)
			(effects
				(font
					(size 1.27 1.27)
					(thickness 0.15)
				)
				(justify left)
			)
		)
		(property "Value" "Fiducial_1mm_Mask2mm"
			(at 152.4 218.44 0)
			(effects
				(font
					(size 1.27 1.27)
					(thickness 0.15)
				)
				(justify left)
			)
		)
		(property "Footprint" "antmicro-footprints:Fiducial_1mm_Mask2mm"
			(at 157.48 222.25 0)
			(effects
				(font
					(size 1.27 1.27)
					(thickness 0.15)
				)
				(justify left bottom)
				(hide yes)
			)
		)
		(property "Datasheet" ""
			(at 157.81 227.66 0)
			(effects
				(font
					(size 1.27 1.27)
					(thickness 0.15)
				)
				(justify left bottom)
				(hide yes)
			)
		)
		(property "Description" "Fiducial mask"
			(at 157.81 230.2 0)
			(effects
				(font
					(size 1.27 1.27)
				)
				(justify left bottom)
				(hide yes)
			)
		)
		(property "Author" "Antmicro"
			(at 157.48 224.79 0)
			(effects
				(font
					(size 1.27 1.27)
					(thickness 0.15)
				)
				(justify left bottom)
				(hide yes)
			)
		)
		(property "License" "Apache-2.0"
			(at 157.48 227.33 0)
			(effects
				(font
					(size 1.27 1.27)
					(thickness 0.15)
				)
				(justify left bottom)
				(hide yes)
			)
		)
		(instances
			(project "thunderbolt-to-10gbe-adapter"
				(path ""
					(reference "FD2")
					(unit 1)
				)
			)
		)
	)
	(symbol
		(lib_id "antmicroMechanicalParts:Lightpipe_Mentor_1271.1001")
		(at 44.45 264.795 0)
		(unit 1)
		(exclude_from_sim no)
		(in_bom yes)
		(on_board yes)
		(dnp no)
		(fields_autoplaced yes)
		(property "Reference" "H3"
			(at 50.292 263.3294 0)
			(effects
				(font
					(size 1.27 1.27)
					(thickness 0.15)
				)
				(justify left)
			)
		)
		(property "Value" "Lightpipe_Mentor_1271.1001"
			(at 64.77 272.415 0)
			(effects
				(font
					(size 1.27 1.27)
					(thickness 0.15)
				)
				(justify left bottom)
				(hide yes)
			)
		)
		(property "Footprint" "antmicro-footprints:Mech_Lightpipe_Mentor_1271.1001"
			(at 64.77 274.955 0)
			(effects
				(font
					(size 1.27 1.27)
					(thickness 0.15)
				)
				(justify left bottom)
				(hide yes)
			)
		)
		(property "Datasheet" "https://www.mentor.de.com/productpdfs/ll/ll14-20.pdf"
			(at 64.77 277.495 0)
			(effects
				(font
					(size 1.27 1.27)
					(thickness 0.15)
				)
				(justify left bottom)
				(hide yes)
			)
		)
		(property "Description" "Light Pipe, 14.45 mm, 1 Pipe, Circular, PC Board, Transparent"
			(at 44.45 264.795 0)
			(effects
				(font
					(size 1.27 1.27)
				)
				(hide yes)
			)
		)
		(property "MPN" "1271.1001"
			(at 50.292 265.8531 0)
			(effects
				(font
					(size 1.27 1.27)
					(thickness 0.15)
				)
				(justify left)
			)
		)
		(property "Manufacturer" "Mentor Worldwide"
			(at 64.77 280.035 0)
			(effects
				(font
					(size 1.27 1.27)
					(thickness 0.15)
				)
				(justify left bottom)
				(hide yes)
			)
		)
		(property "Author" "Antmicro"
			(at 64.77 282.575 0)
			(effects
				(font
					(size 1.27 1.27)
					(thickness 0.15)
				)
				(justify left bottom)
				(hide yes)
			)
		)
		(property "License" "Apache-2.0"
			(at 64.77 285.115 0)
			(effects
				(font
					(size 1.27 1.27)
					(thickness 0.15)
				)
				(justify left bottom)
				(hide yes)
			)
		)
		(instances
			(project "thunderbolt-to-10gbe-adapter"
				(path ""
					(reference "H3")
					(unit 1)
				)
			)
		)
	)
	(symbol
		(lib_id "antmicroMechanicalParts:MP_Pad6mm_Drill3.2mm")
		(at 113.03 259.08 0)
		(unit 1)
		(exclude_from_sim no)
		(in_bom no)
		(on_board yes)
		(dnp no)
		(fields_autoplaced yes)
		(property "Reference" "MP7"
			(at 121.92 257.81 0)
			(effects
				(font
					(size 1.27 1.27)
					(thickness 0.15)
				)
				(justify left)
			)
		)
		(property "Value" "MP_Pad6mm_Drill3.2mm"
			(at 121.92 260.35 0)
			(effects
				(font
					(size 1.27 1.27)
					(thickness 0.15)
				)
				(justify left)
			)
		)
		(property "Footprint" "antmicro-footprints:MP_Pad6mm_Drill3.2mm"
			(at 133.35 266.7 0)
			(effects
				(font
					(size 1.27 1.27)
					(thickness 0.15)
				)
				(justify left bottom)
				(hide yes)
			)
		)
		(property "Datasheet" ""
			(at 129.87 274.65 0)
			(effects
				(font
					(size 1.27 1.27)
					(thickness 0.15)
				)
				(justify left bottom)
				(hide yes)
			)
		)
		(property "Description" "Mechanical part"
			(at 113.03 259.08 0)
			(effects
				(font
					(size 1.27 1.27)
				)
				(hide yes)
			)
		)
		(property "Author" "Antmicro"
			(at 133.35 269.24 0)
			(effects
				(font
					(size 1.27 1.27)
					(thickness 0.15)
				)
				(justify left bottom)
				(hide yes)
			)
		)
		(property "License" "Apache-2.0"
			(at 133.35 271.78 0)
			(effects
				(font
					(size 1.27 1.27)
					(thickness 0.15)
				)
				(justify left bottom)
				(hide yes)
			)
		)
		(pin "1"
		)
		(instances
			(project "oculink-to-10gbe-adapter"
				(path ""
					(reference "MP7")
					(unit 1)
				)
			)
			(project "thunderbolt-to-10gbe-adapter"
				(path ""
					(reference "MP7")
					(unit 1)
				)
			)
		)
	)
	(symbol
		(lib_id "antmicroMechanicalParts:Heatsink_ATS-61500R-C2-R0")
		(at 39.37 243.84 0)
		(unit 1)
		(exclude_from_sim no)
		(in_bom yes)
		(on_board yes)
		(dnp no)
		(property "Reference" "H1"
			(at 45.72 244.7925 0)
			(effects
				(font
					(size 1.27 1.27)
					(thickness 0.15)
				)
				(justify left)
			)
		)
		(property "Value" "Heatsink_ATS-61500R-C2-R0"
			(at 45.72 247.3325 0)
			(effects
				(font
					(size 1.27 1.27)
					(thickness 0.15)
				)
				(justify left)
				(hide yes)
			)
		)
		(property "Footprint" "antmicro-footprints:Heatsink_ATS-61500R-C2-R0"
			(at 57.15 251.46 0)
			(effects
				(font
					(size 1.27 1.27)
					(thickness 0.15)
				)
				(justify left bottom)
				(hide yes)
			)
		)
		(property "Datasheet" "https://www.qats.com/DataSheet/ATS-61500-Series-C2-R0"
			(at 57.15 254 0)
			(effects
				(font
					(size 1.27 1.27)
					(thickness 0.15)
				)
				(justify left bottom)
				(hide yes)
			)
		)
		(property "Description" "Heat Sinks fanSINK Assembly with Mounting Hardware"
			(at 39.37 243.84 0)
			(effects
				(font
					(size 1.27 1.27)
				)
				(hide yes)
			)
		)
		(property "MPN" "ATS-61500R-C2-R0"
			(at 45.974 246.38 0)
			(effects
				(font
					(size 1.27 1.27)
					(thickness 0.15)
				)
				(justify left)
			)
		)
		(property "Manufacturer" "Advanced Thermal Solutions"
			(at 57.15 259.08 0)
			(effects
				(font
					(size 1.27 1.27)
					(thickness 0.15)
				)
				(justify left bottom)
				(hide yes)
			)
		)
		(property "Author" "Antmicro"
			(at 57.15 261.62 0)
			(effects
				(font
					(size 1.27 1.27)
					(thickness 0.15)
				)
				(justify left bottom)
				(hide yes)
			)
		)
		(property "License" "Apache-2.0"
			(at 57.15 264.16 0)
			(effects
				(font
					(size 1.27 1.27)
					(thickness 0.15)
				)
				(justify left bottom)
				(hide yes)
			)
		)
		(instances
			(project "OCuLink to 10GbE adapter"
				(path ""
					(reference "H1")
					(unit 1)
				)
			)
			(project "thunderbolt-to-10gbe-adapter"
				(path ""
					(reference "H1")
					(unit 1)
				)
			)
		)
	)
	(symbol
		(lib_id "antmicroMechanicalParts:Lightpipe_Mentor_1271.1001")
		(at 44.45 273.05 0)
		(unit 1)
		(exclude_from_sim no)
		(in_bom yes)
		(on_board yes)
		(dnp no)
		(fields_autoplaced yes)
		(property "Reference" "H4"
			(at 50.292 271.5844 0)
			(effects
				(font
					(size 1.27 1.27)
					(thickness 0.15)
				)
				(justify left)
			)
		)
		(property "Value" "Lightpipe_Mentor_1271.1001"
			(at 64.77 280.67 0)
			(effects
				(font
					(size 1.27 1.27)
					(thickness 0.15)
				)
				(justify left bottom)
				(hide yes)
			)
		)
		(property "Footprint" "antmicro-footprints:Mech_Lightpipe_Mentor_1271.1001"
			(at 64.77 283.21 0)
			(effects
				(font
					(size 1.27 1.27)
					(thickness 0.15)
				)
				(justify left bottom)
				(hide yes)
			)
		)
		(property "Datasheet" "https://www.mentor.de.com/productpdfs/ll/ll14-20.pdf"
			(at 64.77 285.75 0)
			(effects
				(font
					(size 1.27 1.27)
					(thickness 0.15)
				)
				(justify left bottom)
				(hide yes)
			)
		)
		(property "Description" "Light Pipe, 14.45 mm, 1 Pipe, Circular, PC Board, Transparent"
			(at 44.45 273.05 0)
			(effects
				(font
					(size 1.27 1.27)
				)
				(hide yes)
			)
		)
		(property "MPN" "1271.1001"
			(at 50.292 274.1081 0)
			(effects
				(font
					(size 1.27 1.27)
					(thickness 0.15)
				)
				(justify left)
			)
		)
		(property "Manufacturer" "Mentor Worldwide"
			(at 64.77 288.29 0)
			(effects
				(font
					(size 1.27 1.27)
					(thickness 0.15)
				)
				(justify left bottom)
				(hide yes)
			)
		)
		(property "Author" "Antmicro"
			(at 64.77 290.83 0)
			(effects
				(font
					(size 1.27 1.27)
					(thickness 0.15)
				)
				(justify left bottom)
				(hide yes)
			)
		)
		(property "License" "Apache-2.0"
			(at 64.77 293.37 0)
			(effects
				(font
					(size 1.27 1.27)
					(thickness 0.15)
				)
				(justify left bottom)
				(hide yes)
			)
		)
		(instances
			(project "thunderbolt-to-10gbe-adapter"
				(path ""
					(reference "H4")
					(unit 1)
				)
			)
		)
	)
	(symbol
		(lib_id "antmicropower:GND")
		(at 110.49 269.24 0)
		(unit 1)
		(exclude_from_sim no)
		(in_bom yes)
		(on_board yes)
		(dnp no)
		(property "Reference" "#PWR02"
			(at 119.38 271.78 0)
			(effects
				(font
					(size 1.27 1.27)
					(thickness 0.15)
				)
				(justify left bottom)
				(hide yes)
			)
		)
		(property "Value" "GND"
			(at 110.49 273.05 0)
			(effects
				(font
					(size 1.27 1.27)
					(thickness 0.15)
				)
			)
		)
		(property "Footprint" ""
			(at 119.38 276.86 0)
			(effects
				(font
					(size 1.27 1.27)
					(thickness 0.15)
				)
				(justify left bottom)
				(hide yes)
			)
		)
		(property "Datasheet" ""
			(at 119.38 281.94 0)
			(effects
				(font
					(size 1.27 1.27)
					(thickness 0.15)
				)
				(justify left bottom)
				(hide yes)
			)
		)
		(property "Description" ""
			(at 110.49 269.24 0)
			(effects
				(font
					(size 1.27 1.27)
				)
				(hide yes)
			)
		)
		(property "Author" "Antmicro"
			(at 119.38 276.86 0)
			(effects
				(font
					(size 1.27 1.27)
					(thickness 0.15)
				)
				(justify left bottom)
				(hide yes)
			)
		)
		(property "License" "Apache-2.0"
			(at 119.38 279.4 0)
			(effects
				(font
					(size 1.27 1.27)
					(thickness 0.15)
				)
				(justify left bottom)
				(hide yes)
			)
		)
		(pin "1"
		)
		(instances
			(project "oculink-to-10gbe-adapter"
				(path ""
					(reference "#PWR063")
					(unit 1)
				)
			)
			(project "thunderbolt-to-10gbe-adapter"
				(path ""
					(reference "#PWR02")
					(unit 1)
				)
			)
		)
	)
	(symbol
		(lib_id "antmicroFiducialMarks:Fiducial_1mm_Mask2mm")
		(at 148.59 242.57 0)
		(unit 1)
		(exclude_from_sim no)
		(in_bom no)
		(on_board yes)
		(dnp no)
		(fields_autoplaced yes)
		(property "Reference" "FD7"
			(at 152.4 241.3 0)
			(effects
				(font
					(size 1.27 1.27)
					(thickness 0.15)
				)
				(justify left)
			)
		)
		(property "Value" "Fiducial_1mm_Mask2mm"
			(at 152.4 243.84 0)
			(effects
				(font
					(size 1.27 1.27)
					(thickness 0.15)
				)
				(justify left)
			)
		)
		(property "Footprint" "antmicro-footprints:Fiducial_1mm_Mask2mm"
			(at 157.48 247.65 0)
			(effects
				(font
					(size 1.27 1.27)
					(thickness 0.15)
				)
				(justify left bottom)
				(hide yes)
			)
		)
		(property "Datasheet" ""
			(at 157.81 253.06 0)
			(effects
				(font
					(size 1.27 1.27)
					(thickness 0.15)
				)
				(justify left bottom)
				(hide yes)
			)
		)
		(property "Description" "Fiducial mask"
			(at 157.81 255.6 0)
			(effects
				(font
					(size 1.27 1.27)
				)
				(justify left bottom)
				(hide yes)
			)
		)
		(property "Author" "Antmicro"
			(at 157.48 250.19 0)
			(effects
				(font
					(size 1.27 1.27)
					(thickness 0.15)
				)
				(justify left bottom)
				(hide yes)
			)
		)
		(property "License" "Apache-2.0"
			(at 157.48 252.73 0)
			(effects
				(font
					(size 1.27 1.27)
					(thickness 0.15)
				)
				(justify left bottom)
				(hide yes)
			)
		)
		(instances
			(project "thunderbolt-to-10gbe-adapter"
				(path ""
					(reference "FD7")
					(unit 1)
				)
			)
		)
	)
	(symbol
		(lib_id "antmicropower:GND")
		(at 72.39 269.24 0)
		(unit 1)
		(exclude_from_sim no)
		(in_bom yes)
		(on_board yes)
		(dnp no)
		(property "Reference" "#PWR01"
			(at 81.28 271.78 0)
			(effects
				(font
					(size 1.27 1.27)
					(thickness 0.15)
				)
				(justify left bottom)
				(hide yes)
			)
		)
		(property "Value" "GND"
			(at 72.39 273.05 0)
			(effects
				(font
					(size 1.27 1.27)
					(thickness 0.15)
				)
			)
		)
		(property "Footprint" ""
			(at 81.28 276.86 0)
			(effects
				(font
					(size 1.27 1.27)
					(thickness 0.15)
				)
				(justify left bottom)
				(hide yes)
			)
		)
		(property "Datasheet" ""
			(at 81.28 281.94 0)
			(effects
				(font
					(size 1.27 1.27)
					(thickness 0.15)
				)
				(justify left bottom)
				(hide yes)
			)
		)
		(property "Description" ""
			(at 72.39 269.24 0)
			(effects
				(font
					(size 1.27 1.27)
				)
				(hide yes)
			)
		)
		(property "Author" "Antmicro"
			(at 81.28 276.86 0)
			(effects
				(font
					(size 1.27 1.27)
					(thickness 0.15)
				)
				(justify left bottom)
				(hide yes)
			)
		)
		(property "License" "Apache-2.0"
			(at 81.28 279.4 0)
			(effects
				(font
					(size 1.27 1.27)
					(thickness 0.15)
				)
				(justify left bottom)
				(hide yes)
			)
		)
		(pin "1"
		)
		(instances
			(project "OCuLink to 10GbE adapter"
				(path ""
					(reference "#PWR01")
					(unit 1)
				)
			)
			(project "thunderbolt-to-10gbe-adapter"
				(path ""
					(reference "#PWR01")
					(unit 1)
				)
			)
		)
	)
	(sheet
		(at 97.79 86.995)
		(size 44.45 74.295)
		(exclude_from_sim no)
		(in_bom yes)
		(on_board yes)
		(dnp no)
		(fields_autoplaced yes)
		(stroke
			(width 0.1524)
			(type solid)
		)
		(fill
			(color 0 0 0 0.0000)
		)
		(property "Sheetname" "TB Controller"
			(at 97.79 86.2834 0)
			(effects
				(font
					(size 1.27 1.27)
				)
				(justify left bottom)
			)
		)
		(property "Sheetfile" "tb.kicad_sch"
			(at 97.79 161.8746 0)
			(effects
				(font
					(size 1.27 1.27)
				)
				(justify left top)
			)
		)
		(pin "I2C1{I2C}" bidirectional
			(at 97.79 118.11 180)
			(effects
				(font
					(size 1.27 1.27)
				)
				(justify left)
			)
		)
		(pin "REFCLK{CLK}" output
			(at 142.24 151.13 0)
			(effects
				(font
					(size 1.27 1.27)
				)
				(justify right)
			)
		)
		(pin "TB_FLASH{SPI}" bidirectional
			(at 97.79 121.92 180)
			(effects
				(font
					(size 1.27 1.27)
				)
				(justify left)
			)
		)
		(pin "USB3{USB_3.0}" bidirectional
			(at 97.79 114.3 180)
			(effects
				(font
					(size 1.27 1.27)
				)
				(justify left)
			)
		)
		(pin "~{PE_RST}" output
			(at 142.24 140.97 0)
			(effects
				(font
					(size 1.27 1.27)
				)
				(justify right)
			)
		)
		(pin "~{PE_WAKE}" input
			(at 142.24 143.51 0)
			(effects
				(font
					(size 1.27 1.27)
				)
				(justify right)
			)
		)
		(pin "LSX_1{LSX}" bidirectional
			(at 97.79 102.87 180)
			(effects
				(font
					(size 1.27 1.27)
				)
				(justify left)
			)
		)
		(pin "HPD" input
			(at 97.79 99.06 180)
			(effects
				(font
					(size 1.27 1.27)
				)
				(justify left)
			)
		)
		(pin "RESET_N" input
			(at 97.79 95.25 180)
			(effects
				(font
					(size 1.27 1.27)
				)
				(justify left)
			)
		)
		(pin "FLASH_WP" output
			(at 97.79 144.78 180)
			(effects
				(font
					(size 1.27 1.27)
				)
				(justify left)
			)
		)
		(pin "AUX{AUX_TB}" bidirectional
			(at 97.79 110.49 180)
			(effects
				(font
					(size 1.27 1.27)
				)
				(justify left)
			)
		)
		(pin "USB_RP{USB}" bidirectional
			(at 97.79 106.68 180)
			(effects
				(font
					(size 1.27 1.27)
				)
				(justify left)
			)
		)
		(pin "PCIex4{PCIe}" bidirectional
			(at 142.24 148.59 0)
			(effects
				(font
					(size 1.27 1.27)
				)
				(justify right)
			)
		)
		(instances
			(project "thunderbolt-to-10gbe-adapter"
				(path ""
					(page "4")
				)
			)
		)
	)
	(sheet
		(at 231.14 138.43)
		(size 43.18 36.83)
		(exclude_from_sim no)
		(in_bom yes)
		(on_board yes)
		(dnp no)
		(fields_autoplaced yes)
		(stroke
			(width 0.1524)
			(type solid)
		)
		(fill
			(color 0 0 0 0.0000)
		)
		(property "Sheetname" "X710-AT2 PCIe"
			(at 231.14 137.7184 0)
			(effects
				(font
					(size 1.27 1.27)
				)
				(justify left bottom)
			)
		)
		(property "Sheetfile" "x710-at2-pcie.kicad_sch"
			(at 231.14 175.8446 0)
			(effects
				(font
					(size 1.27 1.27)
				)
				(justify left top)
			)
		)
		(pin "~{PE_RST}" input
			(at 231.14 140.97 180)
			(effects
				(font
					(size 1.27 1.27)
				)
				(justify left)
			)
		)
		(pin "REFCLK{CLK}" input
			(at 231.14 151.13 180)
			(effects
				(font
					(size 1.27 1.27)
				)
				(justify left)
			)
		)
		(pin "~{PE_WAKE}" output
			(at 231.14 143.51 180)
			(effects
				(font
					(size 1.27 1.27)
				)
				(justify left)
			)
		)
		(pin "PCIex4{PCIe}" bidirectional
			(at 231.14 148.59 180)
			(effects
				(font
					(size 1.27 1.27)
				)
				(justify left)
			)
		)
		(instances
			(project "oculink-to-10gbe-adapter"
				(path ""
					(page "7")
				)
			)
			(project "thunderbolt-to-10gbe-adapter"
				(path ""
					(page "9")
				)
			)
		)
	)
	(sheet
		(at 185.42 167.64)
		(size 30.48 15.24)
		(exclude_from_sim no)
		(in_bom yes)
		(on_board yes)
		(dnp no)
		(fields_autoplaced yes)
		(stroke
			(width 0.1524)
			(type solid)
		)
		(fill
			(color 0 0 0 0.0000)
		)
		(property "Sheetname" "X710 DCDC converters"
			(at 185.42 166.9284 0)
			(effects
				(font
					(size 1.27 1.27)
				)
				(justify left bottom)
			)
		)
		(property "Sheetfile" "DCDC_converters_X710.kicad_sch"
			(at 185.42 183.4646 0)
			(effects
				(font
					(size 1.27 1.27)
				)
				(justify left top)
			)
		)
		(pin "EN" input
			(at 185.42 175.26 180)
			(effects
				(font
					(size 1.27 1.27)
				)
				(justify left)
			)
		)
		(instances
			(project "oculink-to-10gbe-adapter"
				(path ""
					(page "2")
				)
			)
			(project "thunderbolt-to-10gbe-adapter"
				(path ""
					(page "7")
				)
			)
		)
	)
	(sheet
		(at 39.37 86.36)
		(size 30.48 40.005)
		(exclude_from_sim no)
		(in_bom yes)
		(on_board yes)
		(dnp no)
		(stroke
			(width 0.1524)
			(type solid)
		)
		(fill
			(color 0 0 0 0.0000)
		)
		(property "Sheetname" "PD and TB DC-DC"
			(at 39.37 85.6484 0)
			(effects
				(font
					(size 1.27 1.27)
				)
				(justify left bottom)
			)
		)
		(property "Sheetfile" "PD_and_TB_DC_DC.kicad_sch"
			(at 39.37 126.746 0)
			(effects
				(font
					(size 1.27 1.27)
				)
				(justify left top)
			)
		)
		(pin "USB3{USB_3.0}" bidirectional
			(at 69.85 114.3 0)
			(effects
				(font
					(size 1.27 1.27)
				)
				(justify right)
			)
		)
		(pin "I2C1{I2C}" bidirectional
			(at 69.85 118.11 0)
			(effects
				(font
					(size 1.27 1.27)
				)
				(justify right)
			)
		)
		(pin "TB_FLASH{SPI}" bidirectional
			(at 69.85 121.92 0)
			(effects
				(font
					(size 1.27 1.27)
				)
				(justify right)
			)
		)
		(pin "LSX_1{LSX}" bidirectional
			(at 69.85 102.87 0)
			(effects
				(font
					(size 1.27 1.27)
				)
				(justify right)
			)
		)
		(pin "AUX{AUX_TB}" bidirectional
			(at 69.85 110.49 0)
			(effects
				(font
					(size 1.27 1.27)
				)
				(justify right)
			)
		)
		(pin "USB_RP{USB}" bidirectional
			(at 69.85 106.68 0)
			(effects
				(font
					(size 1.27 1.27)
				)
				(justify right)
			)
		)
		(pin "HPD" output
			(at 69.85 99.06 0)
			(effects
				(font
					(size 1.27 1.27)
				)
				(justify right)
			)
		)
		(pin "RESET_N" output
			(at 69.85 95.25 0)
			(effects
				(font
					(size 1.27 1.27)
				)
				(justify right)
			)
		)
		(instances
			(project "thunderbolt-to-10gbe-adapter"
				(path ""
					(page "3")
				)
			)
		)
	)
	(sheet
		(at 289.56 59.69)
		(size 43.18 39.37)
		(exclude_from_sim no)
		(in_bom yes)
		(on_board yes)
		(dnp no)
		(fields_autoplaced yes)
		(stroke
			(width 0.1524)
			(type solid)
		)
		(fill
			(color 0 0 0 0.0000)
		)
		(property "Sheetname" "X710-AT2 10GbE"
			(at 289.56 58.9784 0)
			(effects
				(font
					(size 1.27 1.27)
				)
				(justify left bottom)
			)
		)
		(property "Sheetfile" "x710-at2-10gbe.kicad_sch"
			(at 289.56 99.6446 0)
			(effects
				(font
					(size 1.27 1.27)
				)
				(justify left top)
			)
		)
		(pin "MDIO0_I2C0{MDIO}" bidirectional
			(at 289.56 62.23 180)
			(effects
				(font
					(size 1.27 1.27)
				)
				(justify left)
			)
		)
		(pin "~{P0_INT}" input
			(at 289.56 64.77 180)
			(effects
				(font
					(size 1.27 1.27)
				)
				(justify left)
			)
		)
		(pin "~{P0_LED_ACT}" output
			(at 332.74 64.77 0)
			(effects
				(font
					(size 1.27 1.27)
				)
				(justify right)
			)
		)
		(pin "~{P0_LED_LINK_10G}" output
			(at 332.74 67.31 0)
			(effects
				(font
					(size 1.27 1.27)
				)
				(justify right)
			)
		)
		(pin "~{P1_LED_ACT}" output
			(at 332.74 86.36 0)
			(effects
				(font
					(size 1.27 1.27)
				)
				(justify right)
			)
		)
		(pin "~{P1_LED_LINK_10G}" output
			(at 332.74 88.9 0)
			(effects
				(font
					(size 1.27 1.27)
				)
				(justify right)
			)
		)
		(pin "~{P1_INT}" input
			(at 289.56 67.31 180)
			(effects
				(font
					(size 1.27 1.27)
				)
				(justify left)
			)
		)
		(pin "~{PHY_RESET_3V3}" output
			(at 289.56 77.47 180)
			(effects
				(font
					(size 1.27 1.27)
				)
				(justify left)
			)
		)
		(pin "Ethernet_P0{10GbE}" bidirectional
			(at 332.74 62.23 0)
			(effects
				(font
					(size 1.27 1.27)
				)
				(justify right)
			)
		)
		(pin "Ethernet_P1{10GbE}" bidirectional
			(at 332.74 83.82 0)
			(effects
				(font
					(size 1.27 1.27)
				)
				(justify right)
			)
		)
		(instances
			(project "oculink-to-10gbe-adapter"
				(path ""
					(page "8")
				)
			)
			(project "thunderbolt-to-10gbe-adapter"
				(path ""
					(page "12")
				)
			)
		)
	)
	(sheet
		(at 289.56 151.13)
		(size 43.18 15.24)
		(exclude_from_sim no)
		(in_bom yes)
		(on_board yes)
		(dnp no)
		(fields_autoplaced yes)
		(stroke
			(width 0.1524)
			(type solid)
		)
		(fill
			(color 0 0 0 0.0000)
		)
		(property "Sheetname" "X710-AT2 RSVD"
			(at 289.56 150.4184 0)
			(effects
				(font
					(size 1.27 1.27)
				)
				(justify left bottom)
			)
		)
		(property "Sheetfile" "x710-at2-rsvd.kicad_sch"
			(at 289.56 166.9546 0)
			(effects
				(font
					(size 1.27 1.27)
				)
				(justify left top)
			)
		)
		(instances
			(project "oculink-to-10gbe-adapter"
				(path ""
					(page "10")
				)
			)
			(project "thunderbolt-to-10gbe-adapter"
				(path ""
					(page "10")
				)
			)
		)
	)
	(sheet
		(at 185.42 71.12)
		(size 30.48 15.24)
		(exclude_from_sim no)
		(in_bom yes)
		(on_board yes)
		(dnp no)
		(fields_autoplaced yes)
		(stroke
			(width 0.1524)
			(type solid)
		)
		(fill
			(color 0 0 0 0.0000)
		)
		(property "Sheetname" "X710 flash memory"
			(at 185.42 70.4084 0)
			(effects
				(font
					(size 1.27 1.27)
				)
				(justify left bottom)
			)
		)
		(property "Sheetfile" "flash_x710.kicad_sch"
			(at 185.42 86.9446 0)
			(effects
				(font
					(size 1.27 1.27)
				)
				(justify left top)
			)
		)
		(pin "FLASH{SPI}" bidirectional
			(at 215.9 73.66 0)
			(effects
				(font
					(size 1.27 1.27)
				)
				(justify right)
			)
		)
		(instances
			(project "thunderbolt-to-10gbe-adapter"
				(path ""
					(page "15")
				)
			)
		)
	)
	(sheet
		(at 289.56 128.27)
		(size 43.18 15.24)
		(exclude_from_sim no)
		(in_bom yes)
		(on_board yes)
		(dnp no)
		(fields_autoplaced yes)
		(stroke
			(width 0.1524)
			(type solid)
		)
		(fill
			(color 0 0 0 0.0000)
		)
		(property "Sheetname" "X710-AT2 power"
			(at 289.56 127.5584 0)
			(effects
				(font
					(size 1.27 1.27)
				)
				(justify left bottom)
			)
		)
		(property "Sheetfile" "x710-at2-power.kicad_sch"
			(at 289.56 144.0946 0)
			(effects
				(font
					(size 1.27 1.27)
				)
				(justify left top)
			)
		)
		(instances
			(project "oculink-to-10gbe-adapter"
				(path ""
					(page "6")
				)
			)
			(project "thunderbolt-to-10gbe-adapter"
				(path ""
					(page "8")
				)
			)
		)
	)
	(sheet
		(at 46.99 212.09)
		(size 30.48 15.24)
		(exclude_from_sim no)
		(in_bom yes)
		(on_board yes)
		(dnp no)
		(fields_autoplaced yes)
		(stroke
			(width 0.1524)
			(type solid)
		)
		(fill
			(color 0 0 0 0.0000)
		)
		(property "Sheetname" "Power input"
			(at 46.99 211.3784 0)
			(effects
				(font
					(size 1.27 1.27)
				)
				(justify left bottom)
			)
		)
		(property "Sheetfile" "power_input.kicad_sch"
			(at 46.99 227.9146 0)
			(effects
				(font
					(size 1.27 1.27)
				)
				(justify left top)
			)
		)
		(instances
			(project "thunderbolt-to-10gbe-adapter"
				(path ""
					(page "16")
				)
			)
		)
	)
	(sheet
		(at 39.37 62.23)
		(size 30.48 15.24)
		(exclude_from_sim no)
		(in_bom yes)
		(on_board yes)
		(dnp no)
		(fields_autoplaced yes)
		(stroke
			(width 0.1524)
			(type solid)
		)
		(fill
			(color 0 0 0 0.0000)
		)
		(property "Sheetname" "USB-C connector"
			(at 39.37 61.5184 0)
			(effects
				(font
					(size 1.27 1.27)
				)
				(justify left bottom)
			)
		)
		(property "Sheetfile" "USB-C_connector.kicad_sch"
			(at 39.37 78.0546 0)
			(effects
				(font
					(size 1.27 1.27)
				)
				(justify left top)
			)
		)
		(pin "USB3{USB_3.0}" bidirectional
			(at 69.85 64.77 0)
			(effects
				(font
					(size 1.27 1.27)
				)
				(justify right)
			)
		)
		(instances
			(project "thunderbolt-to-10gbe-adapter"
				(path ""
					(page "2")
				)
			)
		)
	)
	(sheet
		(at 97.79 167.64)
		(size 44.45 15.24)
		(exclude_from_sim no)
		(in_bom yes)
		(on_board yes)
		(dnp no)
		(fields_autoplaced yes)
		(stroke
			(width 0.1524)
			(type solid)
		)
		(fill
			(color 0 0 0 0.0000)
		)
		(property "Sheetname" "TB Controller - Power"
			(at 97.79 166.9284 0)
			(effects
				(font
					(size 1.27 1.27)
				)
				(justify left bottom)
			)
		)
		(property "Sheetfile" "tb-power.kicad_sch"
			(at 97.79 183.4646 0)
			(effects
				(font
					(size 1.27 1.27)
				)
				(justify left top)
			)
		)
		(pin "0P9_BUFFERED" output
			(at 142.24 175.26 0)
			(effects
				(font
					(size 1.27 1.27)
				)
				(justify right)
			)
		)
		(instances
			(project "thunderbolt-to-10gbe-adapter"
				(path ""
					(page "5")
				)
			)
		)
	)
	(sheet
		(at 355.6 59.69)
		(size 44.45 54.61)
		(exclude_from_sim no)
		(in_bom yes)
		(on_board yes)
		(dnp no)
		(fields_autoplaced yes)
		(stroke
			(width 0.1016)
			(type solid)
		)
		(fill
			(color 0 0 0 0.0000)
		)
		(property "Sheetname" "2xRJ45"
			(at 355.6 59.0038 0)
			(effects
				(font
					(size 1.27 1.27)
				)
				(justify left bottom)
			)
		)
		(property "Sheetfile" "2xrj45.kicad_sch"
			(at 355.6 114.8592 0)
			(effects
				(font
					(size 1.27 1.27)
				)
				(justify left top)
			)
		)
		(pin "~{P0_LED_ACT}" input
			(at 355.6 64.77 180)
			(effects
				(font
					(size 1.27 1.27)
				)
				(justify left)
			)
		)
		(pin "~{P0_LED_LINK_10G}" input
			(at 355.6 67.31 180)
			(effects
				(font
					(size 1.27 1.27)
				)
				(justify left)
			)
		)
		(pin "~{P0_LINK_LESS_THAN_10G}" input
			(at 355.6 106.68 180)
			(effects
				(font
					(size 1.27 1.27)
				)
				(justify left)
			)
		)
		(pin "~{P1_LED_ACT}" input
			(at 355.6 86.36 180)
			(effects
				(font
					(size 1.27 1.27)
				)
				(justify left)
			)
		)
		(pin "~{P1_LED_LINK_10G}" input
			(at 355.6 88.9 180)
			(effects
				(font
					(size 1.27 1.27)
				)
				(justify left)
			)
		)
		(pin "~{P1_LINK_LESS_THAN_10G}" input
			(at 355.6 109.22 180)
			(effects
				(font
					(size 1.27 1.27)
				)
				(justify left)
			)
		)
		(pin "Ethernet_P0{10GbE}" bidirectional
			(at 355.6 62.23 180)
			(effects
				(font
					(size 1.27 1.27)
				)
				(justify left)
			)
		)
		(pin "Ethernet_P1{10GbE}" bidirectional
			(at 355.6 83.82 180)
			(effects
				(font
					(size 1.27 1.27)
				)
				(justify left)
			)
		)
		(instances
			(project "oculink-to-10gbe-adapter"
				(path ""
					(page "4")
				)
			)
			(project "thunderbolt-to-10gbe-adapter"
				(path ""
					(page "13")
				)
			)
		)
	)
	(sheet
		(at 39.37 132.08)
		(size 30.48 15.24)
		(exclude_from_sim no)
		(in_bom yes)
		(on_board yes)
		(dnp no)
		(fields_autoplaced yes)
		(stroke
			(width 0.1524)
			(type solid)
		)
		(fill
			(color 0 0 0 0.0000)
		)
		(property "Sheetname" "TB flash memory"
			(at 39.37 131.3684 0)
			(effects
				(font
					(size 1.27 1.27)
				)
				(justify left bottom)
			)
		)
		(property "Sheetfile" "flash-memory.kicad_sch"
			(at 39.37 147.9046 0)
			(effects
				(font
					(size 1.27 1.27)
				)
				(justify left top)
			)
		)
		(pin "FLASH_WP" input
			(at 69.85 144.78 0)
			(effects
				(font
					(size 1.27 1.27)
				)
				(justify right)
			)
		)
		(pin "TB_FLASH{SPI}" bidirectional
			(at 69.85 134.62 0)
			(effects
				(font
					(size 1.27 1.27)
				)
				(justify right)
			)
		)
		(instances
			(project "oculink-to-10gbe-adapter"
				(path ""
					(page "3")
				)
			)
			(project "thunderbolt-to-10gbe-adapter"
				(path ""
					(page "6")
				)
			)
		)
	)
	(sheet
		(at 104.775 212.09)
		(size 30.48 15.24)
		(exclude_from_sim no)
		(in_bom yes)
		(on_board yes)
		(dnp no)
		(fields_autoplaced yes)
		(stroke
			(width 0.1524)
			(type solid)
		)
		(fill
			(color 0 0 0 0.0000)
		)
		(property "Sheetname" "Fan controller"
			(at 104.775 211.3784 0)
			(effects
				(font
					(size 1.27 1.27)
				)
				(justify left bottom)
			)
		)
		(property "Sheetfile" "fan-controller.kicad_sch"
			(at 104.775 227.9146 0)
			(effects
				(font
					(size 1.27 1.27)
				)
				(justify left top)
			)
		)
		(instances
			(project "oculink-to-10gbe-adapter"
				(path ""
					(page "13")
				)
			)
			(project "thunderbolt-to-10gbe-adapter"
				(path ""
					(page "14")
				)
			)
		)
	)
	(sheet
		(at 231.14 59.69)
		(size 43.18 71.12)
		(exclude_from_sim no)
		(in_bom yes)
		(on_board yes)
		(dnp no)
		(fields_autoplaced yes)
		(stroke
			(width 0.1524)
			(type solid)
		)
		(fill
			(color 0 0 0 0.0000)
		)
		(property "Sheetname" "X710-AT2 Misc"
			(at 231.14 58.9784 0)
			(effects
				(font
					(size 1.27 1.27)
				)
				(justify left bottom)
			)
		)
		(property "Sheetfile" "x710-at2-mics.kicad_sch"
			(at 231.14 131.3946 0)
			(effects
				(font
					(size 1.27 1.27)
				)
				(justify left top)
			)
		)
		(pin "FLASH{SPI}" bidirectional
			(at 231.14 73.66 180)
			(effects
				(font
					(size 1.27 1.27)
				)
				(justify left)
			)
		)
		(pin "~{PE_RST}" input
			(at 231.14 95.25 180)
			(effects
				(font
					(size 1.27 1.27)
				)
				(justify left)
			)
		)
		(pin "~{P0_LINK_LESS_THAN_10G}" output
			(at 274.32 106.68 0)
			(effects
				(font
					(size 1.27 1.27)
				)
				(justify right)
			)
		)
		(pin "~{P1_LINK_LESS_THAN_10G}" output
			(at 274.32 109.22 0)
			(effects
				(font
					(size 1.27 1.27)
				)
				(justify right)
			)
		)
		(pin "P0_INT_MLC" output
			(at 274.32 64.77 0)
			(effects
				(font
					(size 1.27 1.27)
				)
				(justify right)
			)
		)
		(pin "P1_INT_MLC" output
			(at 274.32 67.31 0)
			(effects
				(font
					(size 1.27 1.27)
				)
				(justify right)
			)
		)
		(pin "MDIO_I2C{MDIO}" bidirectional
			(at 274.32 62.23 0)
			(effects
				(font
					(size 1.27 1.27)
				)
				(justify right)
			)
		)
		(pin "~{PHY_RESET_3V3}" input
			(at 274.32 77.47 0)
			(effects
				(font
					(size 1.27 1.27)
				)
				(justify right)
			)
		)
		(instances
			(project "oculink-to-10gbe-adapter"
				(path ""
					(page "9")
				)
			)
			(project "thunderbolt-to-10gbe-adapter"
				(path ""
					(page "11")
				)
			)
		)
	)
	(sheet_instances
		(path "/"
			(page "1")
		)
	)
)
